(kicad_pcb
	(version 20260206)
	(generator "pcbnew")
	(generator_version "10.0")
	(general
		(thickness 1.6)
		(legacy_teardrops no)
	)
	(paper "A4")
	(title_block
		(title "panther-plus-userver — 13130-1b_20150205.brd")
		(comment 1 "Honey Badger (Wiwynn) / footprint 282 of 1509 (U13), pads 705-819 of 1283")
	)
	(layers
		(0 "F.Cu" signal "TOP")
		(4 "In1.Cu" signal "L2")
		(6 "In2.Cu" signal "L3")
		(8 "In3.Cu" signal "L4")
		(10 "In4.Cu" signal "L5")
		(12 "In5.Cu" signal "L6")
		(14 "In6.Cu" signal "L7")
		(16 "In7.Cu" signal "L8")
		(18 "In8.Cu" signal "L9")
		(20 "In9.Cu" signal "L10")
		(22 "In10.Cu" signal "L11")
		(2 "B.Cu" signal "BOTTOM")
		(9 "F.Adhes" user "F.Adhesive")
		(11 "B.Adhes" user "B.Adhesive")
		(13 "F.Paste" user "Package Geometry/Pastemask Top")
		(15 "B.Paste" user "Package Geometry/Pastemask Bottom")
		(5 "F.SilkS" user "Ref Des/Silkscreen Top")
		(7 "B.SilkS" user "Ref Des/Silkscreen Bottom")
		(1 "F.Mask" user "Board Geometry/Soldermask Top")
		(3 "B.Mask" user "Board Geometry/Soldermask Bottom")
		(17 "Dwgs.User" user "User.Drawings")
		(19 "Cmts.User" user "User.Comments")
		(21 "Eco1.User" user "User.Eco1")
		(23 "Eco2.User" user "User.Eco2")
		(25 "Edge.Cuts" user "Board Geometry/Outline")
		(27 "Margin" user)
		(31 "F.CrtYd" user "Package Geometry/Place Bound Top")
		(29 "B.CrtYd" user "Package Geometry/Place Bound Bottom")
		(35 "F.Fab" user "Ref Des/Assembly Top")
		(33 "B.Fab" user "Ref Des/Assembly Bottom")
	)
	(footprint ""
		(layer "F.Cu")
		(at 95.849948 -39.200074 180)
		(property "Reference" "U13"
			(at 0 0 180)
			(layer "F.SilkS")
			(hide yes)
			(effects
				(font
					(size 1.27 1.27)
				)
			)
		)
		(property "Value" "AVOTON-GP"
			(at -25.0317 -2.4892 180)
			(unlocked yes)
			(layer "F.Fab")
			(hide yes)
			(effects
				(font
					(size 1.016 1.016)
					(thickness 0.1524)
				)
			)
		)
		(property "Device Type" "BGA1283M3428-3H197"
			(at -25.0317 -4.0132 180)
			(unlocked yes)
			(layer "F.Fab")
			(hide yes)
			(effects
				(font
					(size 1.016 1.016)
					(thickness 0.1524)
				)
			)
		)
		(duplicate_pad_numbers_are_jumpers no)
		(pad "BJ66" smd circle
			(at 16.11122 10.67308 180)
			(size 0.4064 0.4064)
			(layers "F.Cu" "F.Mask" "F.Paste")
			(net "GND")
		)
		(pad "BK1" smd circle
			(at -16.11122 11.48588 180)
			(size 0.4064 0.4064)
			(layers "F.Cu" "F.Mask" "F.Paste")
			(net "GND")
		)
		(pad "BK3" smd circle
			(at -15.29842 11.48588 180)
			(size 0.4064 0.4064)
			(layers "F.Cu" "F.Mask" "F.Paste")
			(net "M_A_MON2_N")
		)
		(pad "BK5" smd circle
			(at -14.48562 11.48588 180)
			(size 0.4064 0.4064)
			(layers "F.Cu" "F.Mask" "F.Paste")
			(net "M_A_MON2_P")
		)
		(pad "BK6" smd circle
			(at -13.91666 11.06424 180)
			(size 0.3048 0.3048)
			(layers "F.Cu" "F.Mask" "F.Paste")
			(net "PV_VDDR")
		)
		(pad "BK8" smd circle
			(at -12.89558 11.06424 180)
			(size 0.3048 0.3048)
			(layers "F.Cu" "F.Mask" "F.Paste")
			(net "GND")
		)
		(pad "BK9" smd circle
			(at -12.192 11.01344 180)
			(size 0.3048 0.3048)
			(layers "F.Cu" "F.Mask" "F.Paste")
			(net "PV_VDDR")
		)
		(pad "BK10" smd circle
			(at -11.51382 11.20394 180)
			(size 0.3048 0.3048)
			(layers "F.Cu" "F.Mask" "F.Paste")
			(net "GND")
		)
		(pad "BK12" smd circle
			(at -10.81532 11.20394 180)
			(size 0.3048 0.3048)
			(layers "F.Cu" "F.Mask" "F.Paste")
			(net "PV_VDDR")
		)
		(pad "BK13" smd circle
			(at -10.11936 11.0744 180)
			(size 0.3048 0.3048)
			(layers "F.Cu" "F.Mask" "F.Paste")
			(net "PV_VDDR")
		)
		(pad "BK15" smd circle
			(at -9.41324 11.06424 180)
			(size 0.3048 0.3048)
			(layers "F.Cu" "F.Mask" "F.Paste")
			(net "GND")
		)
		(pad "BK17" smd circle
			(at -8.39216 11.06424 180)
			(size 0.3048 0.3048)
			(layers "F.Cu" "F.Mask" "F.Paste")
			(net "GND")
		)
		(pad "BK18" smd circle
			(at -7.68858 11.01344 180)
			(size 0.3048 0.3048)
			(layers "F.Cu" "F.Mask" "F.Paste")
			(net "GND")
		)
		(pad "BK19" smd circle
			(at -7.0104 11.20394 180)
			(size 0.3048 0.3048)
			(layers "F.Cu" "F.Mask" "F.Paste")
			(net "GND")
		)
		(pad "BK21" smd circle
			(at -6.3119 11.20394 180)
			(size 0.3048 0.3048)
			(layers "F.Cu" "F.Mask" "F.Paste")
			(net "GND")
		)
		(pad "BK22" smd circle
			(at -5.61848 11.0744 180)
			(size 0.3048 0.3048)
			(layers "F.Cu" "F.Mask" "F.Paste")
			(net "GND")
		)
		(pad "BK24" smd circle
			(at -4.90982 11.06424 180)
			(size 0.3048 0.3048)
			(layers "F.Cu" "F.Mask" "F.Paste")
			(net "GND")
		)
		(pad "BK26" smd circle
			(at -3.88874 11.06424 180)
			(size 0.3048 0.3048)
			(layers "F.Cu" "F.Mask" "F.Paste")
			(net "GND")
		)
		(pad "BK27" smd circle
			(at -3.18516 11.01344 180)
			(size 0.3048 0.3048)
			(layers "F.Cu" "F.Mask" "F.Paste")
			(net "GND")
		)
		(pad "BK28" smd circle
			(at -2.50952 11.20394 180)
			(size 0.3048 0.3048)
			(layers "F.Cu" "F.Mask" "F.Paste")
			(net "GND")
		)
		(pad "BK30" smd circle
			(at -1.80848 11.20394 180)
			(size 0.3048 0.3048)
			(layers "F.Cu" "F.Mask" "F.Paste")
			(net "GND")
		)
		(pad "BK31" smd circle
			(at -1.11506 11.0744 180)
			(size 0.3048 0.3048)
			(layers "F.Cu" "F.Mask" "F.Paste")
			(net "GND")
		)
		(pad "BK32" smd circle
			(at -0.4064 11.06424 180)
			(size 0.3048 0.3048)
			(layers "F.Cu" "F.Mask" "F.Paste")
			(net "M_A_DQ57")
		)
		(pad "BK35" smd circle
			(at 0.61468 11.06424 180)
			(size 0.3048 0.3048)
			(layers "F.Cu" "F.Mask" "F.Paste")
			(net "M_A_DQ62")
		)
		(pad "BK36" smd circle
			(at 1.31572 11.01344 180)
			(size 0.3048 0.3048)
			(layers "F.Cu" "F.Mask" "F.Paste")
			(net "GND")
		)
		(pad "BK37" smd circle
			(at 1.9939 11.20394 180)
			(size 0.3048 0.3048)
			(layers "F.Cu" "F.Mask" "F.Paste")
			(net "GND")
		)
		(pad "BK39" smd circle
			(at 2.69494 11.20394 180)
			(size 0.3048 0.3048)
			(layers "F.Cu" "F.Mask" "F.Paste")
			(net "GND")
		)
		(pad "BK40" smd circle
			(at 3.38836 11.0744 180)
			(size 0.3048 0.3048)
			(layers "F.Cu" "F.Mask" "F.Paste")
			(net "P2E_CPU_NGFF_C_TX_DN14")
		)
		(pad "BK42" smd circle
			(at 4.09448 11.06424 180)
			(size 0.3048 0.3048)
			(layers "F.Cu" "F.Mask" "F.Paste")
			(net "GND")
		)
		(pad "BK44" smd circle
			(at 5.1181 11.06424 180)
			(size 0.3048 0.3048)
			(layers "F.Cu" "F.Mask" "F.Paste")
			(net "GND")
		)
		(pad "BK45" smd circle
			(at 5.81914 11.01344 180)
			(size 0.3048 0.3048)
			(layers "F.Cu" "F.Mask" "F.Paste")
			(net "GND")
		)
		(pad "BK46" smd circle
			(at 6.49732 11.20394 180)
			(size 0.3048 0.3048)
			(layers "F.Cu" "F.Mask" "F.Paste")
			(net "GND")
		)
		(pad "BK48" smd circle
			(at 7.19836 11.20394 180)
			(size 0.3048 0.3048)
			(layers "F.Cu" "F.Mask" "F.Paste")
			(net "GND")
		)
		(pad "BK49" smd circle
			(at 7.89178 11.07948 180)
			(size 0.3048 0.3048)
			(layers "F.Cu" "F.Mask" "F.Paste")
			(net "GND")
		)
		(pad "BK51" smd circle
			(at 8.5979 11.06424 180)
			(size 0.3048 0.3048)
			(layers "F.Cu" "F.Mask" "F.Paste")
			(net "GND")
		)
		(pad "BK53" smd circle
			(at 9.61898 11.06424 180)
			(size 0.3048 0.3048)
			(layers "F.Cu" "F.Mask" "F.Paste")
			(net "GND")
		)
		(pad "BK54" smd circle
			(at 10.32256 11.01344 180)
			(size 0.3048 0.3048)
			(layers "F.Cu" "F.Mask" "F.Paste")
			(net "P2E_CPU_SAS_C_TX_DN4")
		)
		(pad "BK56" smd circle
			(at 11.00074 11.20394 180)
			(size 0.3048 0.3048)
			(layers "F.Cu" "F.Mask" "F.Paste")
			(net "GND")
		)
		(pad "BK57" smd circle
			(at 11.69924 11.20394 180)
			(size 0.3048 0.3048)
			(layers "F.Cu" "F.Mask" "F.Paste")
			(net "GND")
		)
		(pad "BK58" smd circle
			(at 12.3952 11.07948 180)
			(size 0.3048 0.3048)
			(layers "F.Cu" "F.Mask" "F.Paste")
			(net "GND")
		)
		(pad "BK60" smd circle
			(at 13.10132 11.06424 180)
			(size 0.3048 0.3048)
			(layers "F.Cu" "F.Mask" "F.Paste")
			(net "P2E_CPU_SAS_C_TX_DP0")
		)
		(pad "BK62" smd circle
			(at 14.48562 11.48588 180)
			(size 0.4064 0.4064)
			(layers "F.Cu" "F.Mask" "F.Paste")
			(net "P2E_CPU_SAS_RX_DN2")
		)
		(pad "BK64" smd circle
			(at 15.29842 11.48588 180)
			(size 0.4064 0.4064)
			(layers "F.Cu" "F.Mask" "F.Paste")
			(net "GND")
		)
		(pad "BK66" smd circle
			(at 16.11122 11.48588 180)
			(size 0.4064 0.4064)
			(layers "F.Cu" "F.Mask" "F.Paste")
			(net "GND")
		)
		(pad "BL7" smd circle
			(at -13.40612 11.54176 180)
			(size 0.3048 0.3048)
			(layers "F.Cu" "F.Mask" "F.Paste")
			(net "PV_VDDR")
		)
		(pad "BL8" smd circle
			(at -12.7254 11.75258 180)
			(size 0.3048 0.3048)
			(layers "F.Cu" "F.Mask" "F.Paste")
			(net "M_A_MA1")
		)
		(pad "BL10" smd circle
			(at -11.61034 11.8999 180)
			(size 0.3048 0.3048)
			(layers "F.Cu" "F.Mask" "F.Paste")
			(net "M_A_BS1")
		)
		(pad "BL12" smd circle
			(at -10.72134 11.8999 180)
			(size 0.3048 0.3048)
			(layers "F.Cu" "F.Mask" "F.Paste")
			(net "M_A_BS0")
		)
		(pad "BL14" smd circle
			(at -9.57072 11.79576 180)
			(size 0.3048 0.3048)
			(layers "F.Cu" "F.Mask" "F.Paste")
			(net "GND")
		)
		(pad "BL16" smd circle
			(at -8.9027 11.54176 180)
			(size 0.3048 0.3048)
			(layers "F.Cu" "F.Mask" "F.Paste")
			(net "M_A_DQ40")
		)
		(pad "BL17" smd circle
			(at -8.22198 11.75258 180)
			(size 0.3048 0.3048)
			(layers "F.Cu" "F.Mask" "F.Paste")
			(net "M_A_DQ41")
		)
		(pad "BL19" smd circle
			(at -7.10692 11.8999 180)
			(size 0.3048 0.3048)
			(layers "F.Cu" "F.Mask" "F.Paste")
			(net "GND")
		)
		(pad "BL21" smd circle
			(at -6.21792 11.8999 180)
			(size 0.3048 0.3048)
			(layers "F.Cu" "F.Mask" "F.Paste")
			(net "M_A_DQ42")
		)
		(pad "BL23" smd circle
			(at -5.0673 11.79576 180)
			(size 0.3048 0.3048)
			(layers "F.Cu" "F.Mask" "F.Paste")
			(net "M_A_DQ52")
		)
		(pad "BL25" smd circle
			(at -4.39928 11.54176 180)
			(size 0.3048 0.3048)
			(layers "F.Cu" "F.Mask" "F.Paste")
			(net "GND")
		)
		(pad "BL26" smd circle
			(at -3.71856 11.75258 180)
			(size 0.3048 0.3048)
			(layers "F.Cu" "F.Mask" "F.Paste")
			(net "M_A_DQS_DN6")
		)
		(pad "BL28" smd circle
			(at -2.60604 11.8999 180)
			(size 0.3048 0.3048)
			(layers "F.Cu" "F.Mask" "F.Paste")
			(net "M_A_DQ50")
		)
		(pad "BL30" smd circle
			(at -1.71704 11.8999 180)
			(size 0.3048 0.3048)
			(layers "F.Cu" "F.Mask" "F.Paste")
			(net "GND")
		)
		(pad "BL32" smd circle
			(at -0.56388 11.79576 180)
			(size 0.3048 0.3048)
			(layers "F.Cu" "F.Mask" "F.Paste")
			(net "M_A_DQ61")
		)
		(pad "BL34" smd circle
			(at 0.10414 11.54176 180)
			(size 0.3048 0.3048)
			(layers "F.Cu" "F.Mask" "F.Paste")
			(net "GND")
		)
		(pad "BL35" smd circle
			(at 0.78232 11.75258 180)
			(size 0.3048 0.3048)
			(layers "F.Cu" "F.Mask" "F.Paste")
			(net "M_A_DQ63")
		)
		(pad "BL37" smd circle
			(at 1.89738 11.8999 180)
			(size 0.3048 0.3048)
			(layers "F.Cu" "F.Mask" "F.Paste")
			(net "GND")
		)
		(pad "BL39" smd circle
			(at 2.78638 11.8999 180)
			(size 0.3048 0.3048)
			(layers "F.Cu" "F.Mask" "F.Paste")
			(net "P2E_CPU_NGFF_C_TX_DN15")
		)
		(pad "BL41" smd circle
			(at 3.937 11.79576 180)
			(size 0.3048 0.3048)
			(layers "F.Cu" "F.Mask" "F.Paste")
			(net "P2E_CPU_NGFF_C_TX_DP13")
		)
		(pad "BL43" smd circle
			(at 4.60756 11.54176 180)
			(size 0.3048 0.3048)
			(layers "F.Cu" "F.Mask" "F.Paste")
			(net "GND")
		)
		(pad "BL44" smd circle
			(at 5.28574 11.75258 180)
			(size 0.3048 0.3048)
			(layers "F.Cu" "F.Mask" "F.Paste")
			(net "P2E_CPU_ETH10G_C_TX_DN11")
		)
		(pad "BL46" smd circle
			(at 6.4008 11.8999 180)
			(size 0.3048 0.3048)
			(layers "F.Cu" "F.Mask" "F.Paste")
			(net "P2E_CPU_ETH10G_C_TX_DN10")
		)
		(pad "BL48" smd circle
			(at 7.2898 11.8999 180)
			(size 0.3048 0.3048)
			(layers "F.Cu" "F.Mask" "F.Paste")
			(net "P2E_CPU_ETH10G_C_TX_DN9")
		)
		(pad "BL50" smd circle
			(at 8.44042 11.79576 180)
			(size 0.3048 0.3048)
			(layers "F.Cu" "F.Mask" "F.Paste")
			(net "P2E_CPU_SAS_C_TX_DN7")
		)
		(pad "BL52" smd circle
			(at 9.10844 11.54176 180)
			(size 0.3048 0.3048)
			(layers "F.Cu" "F.Mask" "F.Paste")
			(net "P2E_CPU_SAS_C_TX_DP6")
		)
		(pad "BL53" smd circle
			(at 9.78916 11.75258 180)
			(size 0.3048 0.3048)
			(layers "F.Cu" "F.Mask" "F.Paste")
			(net "P2E_CPU_SAS_C_TX_DN5")
		)
		(pad "BL55" smd circle
			(at 10.90422 11.8999 180)
			(size 0.3048 0.3048)
			(layers "F.Cu" "F.Mask" "F.Paste")
			(net "P2E_CPU_SAS_C_TX_DP3")
		)
		(pad "BL57" smd circle
			(at 11.79322 11.8999 180)
			(size 0.3048 0.3048)
			(layers "F.Cu" "F.Mask" "F.Paste")
			(net "P2E_CPU_SAS_C_TX_DP2")
		)
		(pad "BL59" smd circle
			(at 12.93368 11.75258 180)
			(size 0.3048 0.3048)
			(layers "F.Cu" "F.Mask" "F.Paste")
			(net "P2E_CPU_SAS_C_TX_DP1")
		)
		(pad "BL61" smd circle
			(at 13.61186 11.54176 180)
			(size 0.3048 0.3048)
			(layers "F.Cu" "F.Mask" "F.Paste")
			(net "P2E_CPU_SAS_C_TX_DN0")
		)
		(pad "BM1" smd circle
			(at -16.11122 12.29868 180)
			(size 0.5588 0.5588)
			(layers "F.Cu" "F.Mask" "F.Paste")
			(net "GND")
		)
		(pad "BM3" smd circle
			(at -15.29842 12.29868 180)
			(size 0.4064 0.4064)
			(layers "F.Cu" "F.Mask" "F.Paste")
			(net "GND")
		)
		(pad "BM5" smd circle
			(at -14.48562 12.29868 180)
			(size 0.4064 0.4064)
			(layers "F.Cu" "F.Mask" "F.Paste")
			(net "GND")
		)
		(pad "BM7" smd circle
			(at -13.40612 12.30376 180)
			(size 0.3048 0.3048)
			(layers "F.Cu" "F.Mask" "F.Paste")
			(net "M_A_MA5")
		)
		(pad "BM9" smd circle
			(at -12.22248 12.24788 180)
			(size 0.3048 0.3048)
			(layers "F.Cu" "F.Mask" "F.Paste")
			(net "PV_VDDR")
		)
		(pad "BM13" smd circle
			(at -10.11174 12.2428 180)
			(size 0.3048 0.3048)
			(layers "F.Cu" "F.Mask" "F.Paste")
			(net "CLK_100M_CPU_MPLL0_DN")
		)
		(pad "BM16" smd circle
			(at -8.9535 12.30376 180)
			(size 0.3048 0.3048)
			(layers "F.Cu" "F.Mask" "F.Paste")
			(net "M_A_DQ44")
		)
		(pad "BM18" smd circle
			(at -7.71906 12.24788 180)
			(size 0.3048 0.3048)
			(layers "F.Cu" "F.Mask" "F.Paste")
			(net "M_A_DQS_DP5")
		)
		(pad "BM22" smd circle
			(at -5.60832 12.2428 180)
			(size 0.3048 0.3048)
			(layers "F.Cu" "F.Mask" "F.Paste")
			(net "GND")
		)
		(pad "BM25" smd circle
			(at -4.45008 12.30376 180)
			(size 0.3048 0.3048)
			(layers "F.Cu" "F.Mask" "F.Paste")
			(net "M_A_DQ48")
		)
		(pad "BM27" smd circle
			(at -3.21564 12.24788 180)
			(size 0.3048 0.3048)
			(layers "F.Cu" "F.Mask" "F.Paste")
			(net "M_A_DQ54")
		)
		(pad "BM31" smd circle
			(at -1.1049 12.2428 180)
			(size 0.3048 0.3048)
			(layers "F.Cu" "F.Mask" "F.Paste")
			(net "M_A_DQ60")
		)
		(pad "BM34" smd circle
			(at 0.05334 12.30376 180)
			(size 0.3048 0.3048)
			(layers "F.Cu" "F.Mask" "F.Paste")
			(net "M_A_DQS_DN7")
		)
		(pad "BM36" smd circle
			(at 1.28524 12.24788 180)
			(size 0.3048 0.3048)
			(layers "F.Cu" "F.Mask" "F.Paste")
			(net "M_A_DQ59")
		)
		(pad "BM40" smd circle
			(at 3.39852 12.2428 180)
			(size 0.3048 0.3048)
			(layers "F.Cu" "F.Mask" "F.Paste")
			(net "P2E_CPU_NGFF_C_TX_DP14")
		)
		(pad "BM43" smd circle
			(at 4.55676 12.30376 180)
			(size 0.3048 0.3048)
			(layers "F.Cu" "F.Mask" "F.Paste")
			(net "P2E_CPU_NGFF_C_TX_DN12")
		)
		(pad "BM45" smd circle
			(at 5.78866 12.24788 180)
			(size 0.3048 0.3048)
			(layers "F.Cu" "F.Mask" "F.Paste")
			(net "GND")
		)
		(pad "BM49" smd circle
			(at 7.90194 12.2428 180)
			(size 0.3048 0.3048)
			(layers "F.Cu" "F.Mask" "F.Paste")
			(net "P2E_CPU_ETH10G_C_TX_DN8")
		)
		(pad "BM52" smd circle
			(at 9.05764 12.30376 180)
			(size 0.3048 0.3048)
			(layers "F.Cu" "F.Mask" "F.Paste")
			(net "P2E_CPU_SAS_C_TX_DN6")
		)
		(pad "BM54" smd circle
			(at 10.29208 12.24788 180)
			(size 0.3048 0.3048)
			(layers "F.Cu" "F.Mask" "F.Paste")
			(net "P2E_CPU_SAS_C_TX_DP4")
		)
		(pad "BM58" smd circle
			(at 12.40282 12.2428 180)
			(size 0.3048 0.3048)
			(layers "F.Cu" "F.Mask" "F.Paste")
			(net "P2E_CPU_SAS_C_TX_DN1")
		)
		(pad "BM61" smd circle
			(at 13.61186 12.30376 180)
			(size 0.3048 0.3048)
			(layers "F.Cu" "F.Mask" "F.Paste")
			(net "GND")
		)
		(pad "BM62" smd circle
			(at 14.48562 12.29868 180)
			(size 0.4064 0.4064)
			(layers "F.Cu" "F.Mask" "F.Paste")
			(net "GND")
		)
		(pad "BM64" smd circle
			(at 15.29842 12.29868 180)
			(size 0.4064 0.4064)
			(layers "F.Cu" "F.Mask" "F.Paste")
			(net "GND")
		)
		(pad "BM66" smd circle
			(at 16.11122 12.29868 180)
			(size 0.5588 0.5588)
			(layers "F.Cu" "F.Mask" "F.Paste")
			(net "GND")
		)
		(pad "BN10" smd circle
			(at -11.61796 12.64158 180)
			(size 0.3048 0.3048)
			(layers "F.Cu" "F.Mask" "F.Paste")
			(net "M_A_MA10")
		)
		(pad "BN12" smd circle
			(at -10.69086 12.63904 180)
			(size 0.3048 0.3048)
			(layers "F.Cu" "F.Mask" "F.Paste")
			(net "CLK_100M_CPU_MPLL0_DP")
		)
		(pad "BN14" smd circle
			(at -9.62406 12.75334 180)
			(size 0.3048 0.3048)
			(layers "F.Cu" "F.Mask" "F.Paste")
			(net "GND")
		)
		(pad "BN17" smd circle
			(at -8.14324 12.80668 180)
			(size 0.3048 0.3048)
			(layers "F.Cu" "F.Mask" "F.Paste")
			(net "M_A_DQS_DN5")
		)
		(pad "BN19" smd circle
			(at -7.11454 12.64158 180)
			(size 0.3048 0.3048)
			(layers "F.Cu" "F.Mask" "F.Paste")
			(net "M_A_DQ47")
		)
		(pad "BN21" smd circle
			(at -6.18744 12.63904 180)
			(size 0.3048 0.3048)
			(layers "F.Cu" "F.Mask" "F.Paste")
			(net "M_A_DQ43")
		)
		(pad "BN23" smd circle
			(at -5.12064 12.75334 180)
			(size 0.3048 0.3048)
			(layers "F.Cu" "F.Mask" "F.Paste")
			(net "M_A_DQ53")
		)
		(pad "BN26" smd circle
			(at -3.63982 12.80668 180)
			(size 0.3048 0.3048)
			(layers "F.Cu" "F.Mask" "F.Paste")
			(net "M_A_DQS_DP6")
		)
		(pad "BN28" smd circle
			(at -2.61112 12.64158 180)
			(size 0.3048 0.3048)
			(layers "F.Cu" "F.Mask" "F.Paste")
			(net "M_A_DQ51")
		)
		(pad "BN30" smd circle
			(at -1.68402 12.63904 180)
			(size 0.3048 0.3048)
			(layers "F.Cu" "F.Mask" "F.Paste")
			(net "GND")
		)
		(pad "BN32" smd circle
			(at -0.61722 12.75334 180)
			(size 0.3048 0.3048)
			(layers "F.Cu" "F.Mask" "F.Paste")
			(net "M_A_DQ56")
		)
		(pad "BN35" smd circle
			(at 0.8636 12.80668 180)
			(size 0.3048 0.3048)
			(layers "F.Cu" "F.Mask" "F.Paste")
			(net "M_A_DQ58")
		)
		(pad "BN37" smd circle
			(at 1.8923 12.64158 180)
			(size 0.3048 0.3048)
			(layers "F.Cu" "F.Mask" "F.Paste")
			(net "GND")
		)
		(pad "BN39" smd circle
			(at 2.8194 12.63904 180)
			(size 0.3048 0.3048)
			(layers "F.Cu" "F.Mask" "F.Paste")
			(net "P2E_CPU_NGFF_C_TX_DP15")
		)
		(pad "BN41" smd circle
			(at 3.8862 12.75334 180)
			(size 0.3048 0.3048)
			(layers "F.Cu" "F.Mask" "F.Paste")
			(net "P2E_CPU_NGFF_C_TX_DN13")
		)
	)
)
